# S9S_MB_2U (Grand Teton) — schematic netlist excerpt (pin names and nets, part order shuffled) for the footprints in the layout excerpt that follows; sources: Cadence DE-HDL packaged netlist, KiCad conversion of 03242023_DA0F0TMBIJ0_F0T_Motherboard_J_brd_V01_OCP.brd

PC2137  Q_CAP  0.1UF 25V 10% X7R  pkg 0402  page 162 : A = P3V3_OCP_V3_2_R ; B = GND
R4662  Q_RES  0 5% EMPTY  pkg 0402LF  page 167 : A = P2E_MB_BMC_TX_C_DN<0> ; B = P2E_MB_BMC_TX_C_R2_DN<0>

(kicad_pcb
	(version 20260206)
	(generator "pcbnew")
	(generator_version "10.0")
	(general
		(thickness 1.6)
		(legacy_teardrops no)
	)
	(paper "A4")
	(title_block
		(title "03242023_DA0F0TMBIJ0_F0T_Motherboard_J_brd_V01_OCP.brd")
		(comment 1 "Grand Teton / footprints 3592-3593 of 6105")
	)
	(layers
		(0 "F.Cu" signal "TOP")
		(4 "In1.Cu" signal "GND")
		(6 "In2.Cu" signal "IN1")
		(8 "In3.Cu" signal "GND1")
		(10 "In4.Cu" signal "IN2")
		(12 "In5.Cu" signal "GND2")
		(14 "In6.Cu" signal "IN3")
		(16 "In7.Cu" signal "GND3")
		(18 "In8.Cu" signal "VCC")
		(20 "In9.Cu" signal "VCC1")
		(22 "In10.Cu" signal "GND4")
		(24 "In11.Cu" signal "IN4")
		(26 "In12.Cu" signal "GND5")
		(28 "In13.Cu" signal "IN5")
		(30 "In14.Cu" signal "GND6")
		(32 "In15.Cu" signal "IN6")
		(34 "In16.Cu" signal "GND7")
		(2 "B.Cu" signal "BOTTOM")
		(9 "F.Adhes" user "F.Adhesive")
		(11 "B.Adhes" user "B.Adhesive")
		(13 "F.Paste" user "Package Geometry/Pastemask Top")
		(15 "B.Paste" user "Package Geometry/Pastemask Bottom")
		(5 "F.SilkS" user "Ref Des/Silkscreen Top")
		(7 "B.SilkS" user "Ref Des/Silkscreen Bottom")
		(1 "F.Mask" user "Board Geometry/Soldermask Top")
		(3 "B.Mask" user "Board Geometry/Soldermask Bottom")
		(17 "Dwgs.User" user "User.Drawings")
		(19 "Cmts.User" user "User.Comments")
		(21 "Eco1.User" user "User.Eco1")
		(23 "Eco2.User" user "User.Eco2")
		(25 "Edge.Cuts" user "Board Geometry/Outline")
		(27 "Margin" user)
		(31 "F.CrtYd" user "Package Geometry/Place Bound Top")
		(29 "B.CrtYd" user "Package Geometry/Place Bound Bottom")
		(35 "F.Fab" user "Ref Des/Assembly Top")
		(33 "B.Fab" user "Ref Des/Assembly Bottom")
	)
	(footprint ""
		(layer "F.Cu")
		(at 72.144382 -58.319924 180)
		(property "Reference" "PC2137"
			(at 0 0 180)
			(layer "F.SilkS")
			(hide yes)
			(effects
				(font
					(size 1.27 1.27)
				)
			)
		)
		(property "Value" ""
			(at 0 0 180)
			(layer "F.Fab")
			(effects
				(font
					(size 1.27 1.27)
				)
			)
		)
		(duplicate_pad_numbers_are_jumpers no)
		(fp_line
			(start 0.7874 0.4064)
			(end -0.7874 0.4064)
			(stroke
				(width 0.1524)
				(type default)
			)
			(layer "F.SilkS")
		)
		(fp_line
			(start 0.7874 -0.4064)
			(end 0.7874 0.4064)
			(stroke
				(width 0.1524)
				(type default)
			)
			(layer "F.SilkS")
		)
		(fp_line
			(start -0.7874 0.4064)
			(end -0.7874 -0.4064)
			(stroke
				(width 0.1524)
				(type default)
			)
			(layer "F.SilkS")
		)
		(fp_line
			(start -0.7874 -0.4064)
			(end 0.7874 -0.4064)
			(stroke
				(width 0.1524)
				(type default)
			)
			(layer "F.SilkS")
		)
		(fp_line
			(start 0.67945 0.3048)
			(end 0.120396 0.3048)
			(stroke
				(width 0.1)
				(type default)
			)
			(layer "F.Fab")
		)
		(fp_line
			(start 0.67945 -0.3048)
			(end 0.67945 0.3048)
			(stroke
				(width 0.1)
				(type default)
			)
			(layer "F.Fab")
		)
		(fp_line
			(start 0.12065 -0.2794)
			(end 0.12065 -0.3048)
			(stroke
				(width 0.1)
				(type default)
			)
			(layer "F.Fab")
		)
		(fp_line
			(start 0.12065 -0.3048)
			(end 0.67945 -0.3048)
			(stroke
				(width 0.1)
				(type default)
			)
			(layer "F.Fab")
		)
		(fp_line
			(start 0.120396 0.3048)
			(end 0.120396 0.2794)
			(stroke
				(width 0.1)
				(type default)
			)
			(layer "F.Fab")
		)
		(fp_line
			(start 0.120396 0.2794)
			(end -0.12065 0.2794)
			(stroke
				(width 0.1)
				(type default)
			)
			(layer "F.Fab")
		)
		(fp_line
			(start -0.12065 0.3048)
			(end -0.67945 0.3048)
			(stroke
				(width 0.1)
				(type default)
			)
			(layer "F.Fab")
		)
		(fp_line
			(start -0.12065 0.2794)
			(end -0.12065 0.3048)
			(stroke
				(width 0.1)
				(type default)
			)
			(layer "F.Fab")
		)
		(fp_line
			(start -0.12065 -0.2794)
			(end 0.12065 -0.2794)
			(stroke
				(width 0.1)
				(type default)
			)
			(layer "F.Fab")
		)
		(fp_line
			(start -0.12065 -0.305054)
			(end -0.12065 -0.2794)
			(stroke
				(width 0.1)
				(type default)
			)
			(layer "F.Fab")
		)
		(fp_line
			(start -0.67945 0.3048)
			(end -0.67945 -0.305054)
			(stroke
				(width 0.1)
				(type default)
			)
			(layer "F.Fab")
		)
		(fp_line
			(start -0.67945 -0.305054)
			(end -0.12065 -0.305054)
			(stroke
				(width 0.1)
				(type default)
			)
			(layer "F.Fab")
		)
		(pad "1" smd circle
			(at -0.40005 0 180)
			(size 0 0)
			(layers "F.Cu" "F.Mask" "F.Paste")
			(net "P3V3_OCP_V3_2_R")
		)
		(pad "2" smd circle
			(at 0.40005 0 180)
			(size 0 0)
			(layers "F.Cu" "F.Mask" "F.Paste")
			(net "GND")
		)
	)
	(footprint ""
		(layer "F.Cu")
		(at 20.485608 -385.066794 -90)
		(property "Reference" "R4662"
			(at 0 0 270)
			(layer "F.SilkS")
			(hide yes)
			(effects
				(font
					(size 1.27 1.27)
				)
			)
		)
		(property "Value" ""
			(at 0 0 270)
			(layer "F.Fab")
			(effects
				(font
					(size 1.27 1.27)
				)
			)
		)
		(duplicate_pad_numbers_are_jumpers no)
		(fp_line
			(start -0.7874 0.4064)
			(end -0.7874 -0.4064)
			(stroke
				(width 0.1524)
				(type default)
			)
			(layer "F.SilkS")
		)
		(fp_line
			(start 0.7874 0.4064)
			(end -0.020066 0.4064)
			(stroke
				(width 0.1524)
				(type default)
			)
			(layer "F.SilkS")
		)
		(fp_line
			(start -0.7874 -0.4064)
			(end 0.7874 -0.4064)
			(stroke
				(width 0.1524)
				(type default)
			)
			(layer "F.SilkS")
		)
		(fp_line
			(start -0.67945 0.3048)
			(end -0.67945 -0.305054)
			(stroke
				(width 0.1)
				(type default)
			)
			(layer "F.Fab")
		)
		(fp_line
			(start -0.12065 0.3048)
			(end -0.67945 0.3048)
			(stroke
				(width 0.1)
				(type default)
			)
			(layer "F.Fab")
		)
		(fp_line
			(start 0.120396 0.3048)
			(end 0.120396 0.2794)
			(stroke
				(width 0.1)
				(type default)
			)
			(layer "F.Fab")
		)
		(fp_line
			(start 0.67945 0.3048)
			(end 0.120396 0.3048)
			(stroke
				(width 0.1)
				(type default)
			)
			(layer "F.Fab")
		)
		(fp_line
			(start -0.12065 0.2794)
			(end -0.12065 0.3048)
			(stroke
				(width 0.1)
				(type default)
			)
			(layer "F.Fab")
		)
		(fp_line
			(start 0.120396 0.2794)
			(end -0.12065 0.2794)
			(stroke
				(width 0.1)
				(type default)
			)
			(layer "F.Fab")
		)
		(fp_line
			(start -0.12065 -0.2794)
			(end 0.12065 -0.2794)
			(stroke
				(width 0.1)
				(type default)
			)
			(layer "F.Fab")
		)
		(fp_line
			(start 0.12065 -0.2794)
			(end 0.12065 -0.3048)
			(stroke
				(width 0.1)
				(type default)
			)
			(layer "F.Fab")
		)
		(fp_line
			(start 0.12065 -0.3048)
			(end 0.67945 -0.3048)
			(stroke
				(width 0.1)
				(type default)
			)
			(layer "F.Fab")
		)
		(fp_line
			(start 0.67945 -0.3048)
			(end 0.67945 0.3048)
			(stroke
				(width 0.1)
				(type default)
			)
			(layer "F.Fab")
		)
		(fp_line
			(start -0.67945 -0.305054)
			(end -0.12065 -0.305054)
			(stroke
				(width 0.1)
				(type default)
			)
			(layer "F.Fab")
		)
		(fp_line
			(start -0.12065 -0.305054)
			(end -0.12065 -0.2794)
			(stroke
				(width 0.1)
				(type default)
			)
			(layer "F.Fab")
		)
		(pad "1" smd rect
			(at -0.40005 0 90)
			(size 0.4572 0.508)
			(layers "F.Cu" "F.Mask" "F.Paste")
			(net "P2E_MB_BMC_TX_C_DN<0>")
		)
		(pad "2" smd rect
			(at 0.40005 0 90)
			(size 0.4572 0.508)
			(layers "F.Cu" "F.Mask" "F.Paste")
			(net "P2E_MB_BMC_TX_C_R2_DN<0>")
		)
	)
)
